(kicad_pcb
	(version 20260206)
	(generator "pcbnew")
	(generator_version "10.0")
	(general
		(thickness 1.21888)
		(legacy_teardrops no)
	)
	(paper "A4")
	(title_block
		(title "timecard-v9 — TimeCard-DC-V9_EXP.PcbDoc")
		(comment 1 "Time Appliance Project (Time Card) / footprints 268-277 of 402")
	)
	(layers
		(0 "F.Cu" signal "TOP")
		(4 "In1.Cu" signal "SGND")
		(6 "In2.Cu" signal "IN1")
		(8 "In3.Cu" signal "IN2")
		(10 "In4.Cu" signal "SGND1")
		(2 "B.Cu" signal "BOTTOM")
		(9 "F.Adhes" user "F.Adhesive")
		(11 "B.Adhes" user "B.Adhesive")
		(13 "F.Paste" user "Top Paste")
		(15 "B.Paste" user "Bottom Paste")
		(5 "F.SilkS" user "Top Overlay")
		(7 "B.SilkS" user "Bottom Overlay")
		(1 "F.Mask" user "Top Solder")
		(3 "B.Mask" user "Bottom Solder")
		(17 "Dwgs.User" user "User.Drawings")
		(19 "Cmts.User" user "User.Comments")
		(21 "Eco1.User" user "User.Eco1")
		(23 "Eco2.User" user "User.Eco2")
		(25 "Edge.Cuts" user)
		(27 "Margin" user)
		(31 "F.CrtYd" user "Top Courtyard")
		(29 "B.CrtYd" user "Bottom Courtyard")
		(35 "F.Fab" user "Top Component Center")
		(33 "B.Fab" user "Bottom Component Center")
	)
	(footprint "Vault:FP-0402-L_1_0_1-W_0_5_0_1-IPC_C"
		(layer "B.Cu")
		(at 99.7216 66.85066 -90)
		(property "Reference" "C18"
			(at 1.16554 -0.593345 90)
			(unlocked yes)
			(layer "B.SilkS")
			(effects
				(font
					(size 0.762 0.762)
					(thickness 0.2286)
				)
				(justify left bottom mirror)
			)
		)
		(property "Value" "0.1uF_25V_0402"
			(at 4.572625 15.71837 0)
			(unlocked yes)
			(layer "B.SilkS")
			(hide yes)
			(effects
				(font
					(size 0.762 0.762)
					(thickness 0.2286)
				)
				(justify left bottom mirror)
			)
		)
		(sheetname "03-POWER")
		(sheetfile "03-POWER.kicad_sch")
		(duplicate_pad_numbers_are_jumpers no)
		(fp_line
			(start 0.65607 0.7)
			(end -0.65606 0.7)
			(stroke
				(width 0.2)
				(type solid)
			)
			(layer "B.SilkS")
		)
		(fp_line
			(start 0.65607 -0.7)
			(end -0.65606 -0.7)
			(stroke
				(width 0.2)
				(type solid)
			)
			(layer "B.SilkS")
		)
		(fp_line
			(start -0.75606 0.4)
			(end -0.75606 -0.4)
			(stroke
				(width 0.2)
				(type solid)
			)
			(layer "B.CrtYd")
		)
		(fp_line
			(start 0.75607 0.4)
			(end -0.75606 0.4)
			(stroke
				(width 0.2)
				(type solid)
			)
			(layer "B.CrtYd")
		)
		(fp_line
			(start 0.75607 0.4)
			(end 0.75607 -0.4)
			(stroke
				(width 0.2)
				(type solid)
			)
			(layer "B.CrtYd")
		)
		(fp_line
			(start 0.75607 -0.4)
			(end -0.75606 -0.4)
			(stroke
				(width 0.2)
				(type solid)
			)
			(layer "B.CrtYd")
		)
		(fp_line
			(start 0 0.5)
			(end 0 -0.5)
			(stroke
				(width 0.1)
				(type solid)
			)
			(layer "B.Fab")
		)
		(fp_line
			(start -0.75606 0.4)
			(end -0.75606 -0.4)
			(stroke
				(width 0.2)
				(type solid)
			)
			(layer "B.Fab")
		)
		(fp_line
			(start 0.75607 0.4)
			(end -0.75606 0.4)
			(stroke
				(width 0.2)
				(type solid)
			)
			(layer "B.Fab")
		)
		(fp_line
			(start 0.75607 0.4)
			(end 0.75607 -0.4)
			(stroke
				(width 0.2)
				(type solid)
			)
			(layer "B.Fab")
		)
		(fp_line
			(start 0.5 0)
			(end -0.49999 0)
			(stroke
				(width 0.1)
				(type solid)
			)
			(layer "B.Fab")
		)
		(fp_line
			(start 0.75607 -0.4)
			(end -0.75606 -0.4)
			(stroke
				(width 0.2)
				(type solid)
			)
			(layer "B.Fab")
		)
		(fp_text user "${REFERENCE}"
			(at -0.00001 -0.09602 90)
			(unlocked yes)
			(layer "B.Fab")
			(effects
				(font
					(face "Arial")
					(size 0.63 0.63)
					(thickness 0.1)
				)
				(justify left bottom mirror)
			)
		)
		(pad "1" smd rect
			(at -0.36553 0 270)
			(size 0.58106 0.51213)
			(layers "B.Cu" "B.Mask" "B.Paste")
			(net "+5.0V")
			(solder_mask_margin 0)
			(solder_paste_margin 0)
		)
		(pad "2" smd rect
			(at 0.36554 0 270)
			(size 0.58106 0.51213)
			(layers "B.Cu" "B.Mask" "B.Paste")
			(net "GND")
			(solder_mask_margin 0)
			(solder_paste_margin 0)
		)
	)
	(footprint "Vault:RESC1005X40X25LL05T05"
		(layer "B.Cu")
		(at 113.56707 84.98575 180)
		(property "Reference" "R51"
			(at -5.325925 -0.161941 0)
			(unlocked yes)
			(layer "B.SilkS")
			(effects
				(font
					(size 0.762 0.762)
					(thickness 0.2286)
				)
				(justify mirror)
			)
		)
		(property "Value" "4.7K_0402"
			(at 1.612045 -2.262391 0)
			(unlocked yes)
			(layer "B.SilkS")
			(hide yes)
			(effects
				(font
					(size 0.762 0.762)
					(thickness 0.2286)
				)
				(justify mirror)
			)
		)
		(sheetname "05-GPS_IMU_SENSORS")
		(sheetfile "05-GPS_IMU_SENSORS.kicad_sch")
		(duplicate_pad_numbers_are_jumpers no)
		(pad "1" smd rect
			(at -0.4 0 90)
			(size 0.45 0.45)
			(layers "B.Cu" "B.Mask" "B.Paste")
			(net "BNO_P3V3")
		)
		(pad "2" smd rect
			(at 0.4 0 90)
			(size 0.45 0.45)
			(layers "B.Cu" "B.Mask" "B.Paste")
			(net "NetR51_2")
		)
	)
	(footprint "Vault:FP-0603-L_1_6_0_2-W_0_8_0-MFG"
		(layer "B.Cu")
		(at 227.3216 71.6162 180)
		(property "Reference" "C20"
			(at -1.336 0.346345 180)
			(unlocked yes)
			(layer "B.SilkS")
			(effects
				(font
					(size 0.762 0.762)
					(thickness 0.2286)
				)
				(justify left bottom mirror)
			)
		)
		(property "Value" "10uF_16V_0603"
			(at 6.5525 -3.826045 0)
			(unlocked yes)
			(layer "B.SilkS")
			(hide yes)
			(effects
				(font
					(size 0.762 0.762)
					(thickness 0.2286)
				)
				(justify left bottom mirror)
			)
		)
		(sheetname "03-POWER")
		(sheetfile "03-POWER.kicad_sch")
		(duplicate_pad_numbers_are_jumpers no)
		(fp_line
			(start 0.9 0.825)
			(end -0.9 0.825)
			(stroke
				(width 0.2)
				(type solid)
			)
			(layer "B.SilkS")
		)
		(fp_line
			(start 0.9 -0.825)
			(end -0.9 -0.825)
			(stroke
				(width 0.2)
				(type solid)
			)
			(layer "B.SilkS")
		)
		(fp_line
			(start 1.15 0.6)
			(end -1.15 0.6)
			(stroke
				(width 0.2)
				(type solid)
			)
			(layer "B.CrtYd")
		)
		(fp_line
			(start 1.15 -0.6)
			(end 1.15 0.6)
			(stroke
				(width 0.2)
				(type solid)
			)
			(layer "B.CrtYd")
		)
		(fp_line
			(start 1.15 -0.6)
			(end -1.15 -0.6)
			(stroke
				(width 0.2)
				(type solid)
			)
			(layer "B.CrtYd")
		)
		(fp_line
			(start -1.15 -0.6)
			(end -1.15 0.6)
			(stroke
				(width 0.2)
				(type solid)
			)
			(layer "B.CrtYd")
		)
		(fp_line
			(start 1.15 0.6)
			(end -1.15 0.6)
			(stroke
				(width 0.2)
				(type solid)
			)
			(layer "B.Fab")
		)
		(fp_line
			(start 1.15 -0.6)
			(end 1.15 0.6)
			(stroke
				(width 0.2)
				(type solid)
			)
			(layer "B.Fab")
		)
		(fp_line
			(start 1.15 -0.6)
			(end -1.15 -0.6)
			(stroke
				(width 0.2)
				(type solid)
			)
			(layer "B.Fab")
		)
		(fp_line
			(start 0.5 0)
			(end -0.5 0)
			(stroke
				(width 0.1)
				(type solid)
			)
			(layer "B.Fab")
		)
		(fp_line
			(start 0 -0.5)
			(end 0 0.5)
			(stroke
				(width 0.1)
				(type solid)
			)
			(layer "B.Fab")
		)
		(fp_line
			(start -1.15 -0.6)
			(end -1.15 0.6)
			(stroke
				(width 0.2)
				(type solid)
			)
			(layer "B.Fab")
		)
		(fp_text user "${REFERENCE}"
			(at -0.00001 -0.09602 360)
			(unlocked yes)
			(layer "B.Fab")
			(effects
				(font
					(face "Arial")
					(size 0.63 0.63)
					(thickness 0.1)
				)
				(justify left bottom mirror)
			)
		)
		(pad "1" smd rect
			(at -0.7 0 180)
			(size 0.7 0.7)
			(layers "B.Cu" "B.Mask" "B.Paste")
			(net "+3.3V")
			(solder_mask_margin 0)
			(solder_paste_margin 0)
		)
		(pad "2" smd rect
			(at 0.7 0 180)
			(size 0.7 0.7)
			(layers "B.Cu" "B.Mask" "B.Paste")
			(net "GND")
			(solder_mask_margin 0)
			(solder_paste_margin 0)
		)
	)
	(footprint "Vault:FP-RT0402-MFG"
		(layer "B.Cu")
		(at 86.55491 63.6412 90)
		(property "Reference" "R27"
			(at -1.7464 -0.160241 270)
			(unlocked yes)
			(layer "B.SilkS")
			(effects
				(font
					(size 0.762 0.762)
					(thickness 0.2286)
				)
				(justify mirror)
			)
		)
		(property "Value" "160_0.5%_0402"
			(at -3.087871 -2.37404 0)
			(unlocked yes)
			(layer "B.SilkS")
			(hide yes)
			(effects
				(font
					(size 0.762 0.762)
					(thickness 0.2286)
				)
				(justify mirror)
			)
		)
		(sheetname "03-POWER")
		(sheetfile "03-POWER.kicad_sch")
		(duplicate_pad_numbers_are_jumpers no)
		(fp_line
			(start -0.5 -0.711)
			(end 0.5 -0.711)
			(stroke
				(width 0.2)
				(type solid)
			)
			(layer "B.SilkS")
		)
		(fp_line
			(start -0.5 0.7)
			(end 0.5 0.7)
			(stroke
				(width 0.2)
				(type solid)
			)
			(layer "B.SilkS")
		)
		(fp_line
			(start 0.85 -0.4)
			(end 0.85 0.4)
			(stroke
				(width 0.2)
				(type solid)
			)
			(layer "B.CrtYd")
		)
		(fp_line
			(start -0.85 -0.4)
			(end 0.85 -0.4)
			(stroke
				(width 0.2)
				(type solid)
			)
			(layer "B.CrtYd")
		)
		(fp_line
			(start -0.85 -0.4)
			(end -0.85 0.4)
			(stroke
				(width 0.2)
				(type solid)
			)
			(layer "B.CrtYd")
		)
		(fp_line
			(start -0.85 0.4)
			(end 0.85 0.4)
			(stroke
				(width 0.2)
				(type solid)
			)
			(layer "B.CrtYd")
		)
		(fp_line
			(start 0 -0.5)
			(end 0 0.5)
			(stroke
				(width 0.1)
				(type solid)
			)
			(layer "B.Fab")
		)
		(fp_line
			(start 0.85 -0.4)
			(end 0.85 0.4)
			(stroke
				(width 0.2)
				(type solid)
			)
			(layer "B.Fab")
		)
		(fp_line
			(start -0.85 -0.4)
			(end 0.85 -0.4)
			(stroke
				(width 0.2)
				(type solid)
			)
			(layer "B.Fab")
		)
		(fp_line
			(start -0.85 -0.4)
			(end -0.85 0.4)
			(stroke
				(width 0.2)
				(type solid)
			)
			(layer "B.Fab")
		)
		(fp_line
			(start -0.5 0)
			(end 0.5 0)
			(stroke
				(width 0.1)
				(type solid)
			)
			(layer "B.Fab")
		)
		(fp_line
			(start -0.85 0.4)
			(end 0.85 0.4)
			(stroke
				(width 0.2)
				(type solid)
			)
			(layer "B.Fab")
		)
		(fp_text user "${REFERENCE}"
			(at -0.00001 -0.10711 270)
			(unlocked yes)
			(layer "B.Fab")
			(effects
				(font
					(face "Arial")
					(size 0.63 0.63)
					(thickness 0.1)
				)
				(justify left bottom mirror)
			)
		)
		(pad "1" smd rect
			(at -0.5 0 90)
			(size 0.5 0.6)
			(layers "B.Cu" "B.Mask" "B.Paste")
			(net "GND")
			(solder_mask_margin 0)
			(solder_paste_margin 0)
		)
		(pad "2" smd rect
			(at 0.5 0 90)
			(size 0.5 0.6)
			(layers "B.Cu" "B.Mask" "B.Paste")
			(net "NetR26_1")
			(solder_mask_margin 0)
			(solder_paste_margin 0)
		)
	)
	(footprint "Vault:RESC1005X40X25NL05T05"
		(layer "B.Cu")
		(at 222.0216 112.5412 -90)
		(property "Reference" "R125"
			(at -0.2282 -1.173069 270)
			(unlocked yes)
			(layer "B.SilkS")
			(effects
				(font
					(size 0.762 0.762)
					(thickness 0.2032)
				)
				(justify mirror)
			)
		)
		(property "Value" "200_1%_0402"
			(at -2.732271 -8.112675 180)
			(unlocked yes)
			(layer "B.SilkS")
			(hide yes)
			(effects
				(font
					(size 0.762 0.762)
					(thickness 0.2032)
				)
				(justify mirror)
			)
		)
		(sheetname "08-DIPSwitches_I2C")
		(sheetfile "08-DIPSwitches_I2C.kicad_sch")
		(duplicate_pad_numbers_are_jumpers no)
		(pad "1" smd rect
			(at -0.45 0 180)
			(size 0.55 0.55)
			(layers "B.Cu" "B.Mask" "B.Paste")
			(net "NetD24_1")
		)
		(pad "2" smd rect
			(at 0.45 0 180)
			(size 0.55 0.55)
			(layers "B.Cu" "B.Mask" "B.Paste")
			(net "DIP_SW_MACSER_SEL")
		)
	)
	(footprint "Vault:FP-0402-L_1_0_1-W_0_5_0_1-IPC_C"
		(layer "B.Cu")
		(at 198.5216 121.1162 180)
		(property "Reference" "C103"
			(at 0.0968 -1.473069 180)
			(unlocked yes)
			(layer "B.SilkS")
			(effects
				(font
					(size 0.762 0.762)
					(thickness 0.2032)
				)
				(justify mirror)
			)
		)
		(property "Value" "0.1uF_25V_0402"
			(at -2.465551 -9.813815 90)
			(unlocked yes)
			(layer "B.SilkS")
			(hide yes)
			(effects
				(font
					(size 0.762 0.762)
					(thickness 0.2032)
				)
				(justify mirror)
			)
		)
		(sheetname "10-M2_GPS")
		(sheetfile "10-M2_GPS.kicad_sch")
		(duplicate_pad_numbers_are_jumpers no)
		(fp_line
			(start 0.65607 0.7)
			(end -0.65607 0.7)
			(stroke
				(width 0.2)
				(type solid)
			)
			(layer "B.SilkS")
		)
		(fp_line
			(start 0.65607 -0.7)
			(end -0.65607 -0.7)
			(stroke
				(width 0.2)
				(type solid)
			)
			(layer "B.SilkS")
		)
		(fp_line
			(start 0.75607 0.4)
			(end -0.75607 0.4)
			(stroke
				(width 0.2)
				(type solid)
			)
			(layer "B.CrtYd")
		)
		(fp_line
			(start 0.75607 -0.4)
			(end 0.75607 0.4)
			(stroke
				(width 0.2)
				(type solid)
			)
			(layer "B.CrtYd")
		)
		(fp_line
			(start 0.75607 -0.4)
			(end -0.75607 -0.4)
			(stroke
				(width 0.2)
				(type solid)
			)
			(layer "B.CrtYd")
		)
		(fp_line
			(start -0.75607 -0.4)
			(end -0.75607 0.4)
			(stroke
				(width 0.2)
				(type solid)
			)
			(layer "B.CrtYd")
		)
		(fp_line
			(start 0.75607 0.4)
			(end -0.75607 0.4)
			(stroke
				(width 0.2)
				(type solid)
			)
			(layer "B.Fab")
		)
		(fp_line
			(start 0.75607 -0.4)
			(end 0.75607 0.4)
			(stroke
				(width 0.2)
				(type solid)
			)
			(layer "B.Fab")
		)
		(fp_line
			(start 0.75607 -0.4)
			(end -0.75607 -0.4)
			(stroke
				(width 0.2)
				(type solid)
			)
			(layer "B.Fab")
		)
		(fp_line
			(start 0.5 0)
			(end -0.5 0)
			(stroke
				(width 0.1)
				(type solid)
			)
			(layer "B.Fab")
		)
		(fp_line
			(start 0 -0.5)
			(end 0 0.5)
			(stroke
				(width 0.1)
				(type solid)
			)
			(layer "B.Fab")
		)
		(fp_line
			(start -0.75607 -0.4)
			(end -0.75607 0.4)
			(stroke
				(width 0.2)
				(type solid)
			)
			(layer "B.Fab")
		)
		(fp_text user "${REFERENCE}"
			(at -0.00001 -0.09602 360)
			(unlocked yes)
			(layer "B.Fab")
			(effects
				(font
					(face "Arial")
					(size 0.63 0.63)
					(thickness 0.1)
				)
				(justify left bottom mirror)
			)
		)
		(pad "1" smd rect
			(at -0.36554 0 180)
			(size 0.58106 0.51213)
			(layers "B.Cu" "B.Mask" "B.Paste")
			(net "GNSS2_P3V3")
			(solder_mask_margin 0)
			(solder_paste_margin 0)
		)
		(pad "2" smd rect
			(at 0.36554 0 180)
			(size 0.58106 0.51213)
			(layers "B.Cu" "B.Mask" "B.Paste")
			(net "GND")
			(solder_mask_margin 0)
			(solder_paste_margin 0)
		)
	)
	(footprint "Vault:FP-0402-L_1_0_1-W_0_5_0_1-IPC_C"
		(layer "B.Cu")
		(at 198.4216 119.2162 180)
		(property "Reference" "C101"
			(at 2.4032 -0.526931 0)
			(unlocked yes)
			(layer "B.SilkS")
			(effects
				(font
					(size 0.762 0.762)
					(thickness 0.2032)
				)
				(justify mirror)
			)
		)
		(property "Value" "0.1uF_25V_0402"
			(at -2.465551 -9.813805 90)
			(unlocked yes)
			(layer "B.SilkS")
			(hide yes)
			(effects
				(font
					(size 0.762 0.762)
					(thickness 0.2032)
				)
				(justify mirror)
			)
		)
		(sheetname "10-M2_GPS")
		(sheetfile "10-M2_GPS.kicad_sch")
		(duplicate_pad_numbers_are_jumpers no)
		(fp_line
			(start 0.65607 0.7)
			(end -0.65606 0.7)
			(stroke
				(width 0.2)
				(type solid)
			)
			(layer "B.SilkS")
		)
		(fp_line
			(start 0.65607 -0.7)
			(end -0.65606 -0.7)
			(stroke
				(width 0.2)
				(type solid)
			)
			(layer "B.SilkS")
		)
		(fp_line
			(start 0.75607 0.4)
			(end -0.75606 0.4)
			(stroke
				(width 0.2)
				(type solid)
			)
			(layer "B.CrtYd")
		)
		(fp_line
			(start 0.75607 -0.4)
			(end 0.75607 0.4)
			(stroke
				(width 0.2)
				(type solid)
			)
			(layer "B.CrtYd")
		)
		(fp_line
			(start 0.75607 -0.4)
			(end -0.75606 -0.4)
			(stroke
				(width 0.2)
				(type solid)
			)
			(layer "B.CrtYd")
		)
		(fp_line
			(start -0.75606 -0.4)
			(end -0.75606 0.4)
			(stroke
				(width 0.2)
				(type solid)
			)
			(layer "B.CrtYd")
		)
		(fp_line
			(start 0.75607 0.4)
			(end -0.75606 0.4)
			(stroke
				(width 0.2)
				(type solid)
			)
			(layer "B.Fab")
		)
		(fp_line
			(start 0.75607 -0.4)
			(end 0.75607 0.4)
			(stroke
				(width 0.2)
				(type solid)
			)
			(layer "B.Fab")
		)
		(fp_line
			(start 0.75607 -0.4)
			(end -0.75606 -0.4)
			(stroke
				(width 0.2)
				(type solid)
			)
			(layer "B.Fab")
		)
		(fp_line
			(start 0.5 0)
			(end -0.5 0)
			(stroke
				(width 0.1)
				(type solid)
			)
			(layer "B.Fab")
		)
		(fp_line
			(start 0 -0.5)
			(end 0 0.5)
			(stroke
				(width 0.1)
				(type solid)
			)
			(layer "B.Fab")
		)
		(fp_line
			(start -0.75606 -0.4)
			(end -0.75606 0.4)
			(stroke
				(width 0.2)
				(type solid)
			)
			(layer "B.Fab")
		)
		(fp_text user "${REFERENCE}"
			(at -0.00001 -0.09602 360)
			(unlocked yes)
			(layer "B.Fab")
			(effects
				(font
					(face "Arial")
					(size 0.63 0.63)
					(thickness 0.1)
				)
				(justify left bottom mirror)
			)
		)
		(pad "1" smd rect
			(at -0.36553 0 180)
			(size 0.58106 0.51213)
			(layers "B.Cu" "B.Mask" "B.Paste")
			(net "GNSS2_P3V3")
			(solder_mask_margin 0)
			(solder_paste_margin 0)
		)
		(pad "2" smd rect
			(at 0.36554 0 180)
			(size 0.58106 0.51213)
			(layers "B.Cu" "B.Mask" "B.Paste")
			(net "GND")
			(solder_mask_margin 0)
			(solder_paste_margin 0)
		)
	)
	(footprint "Vault:RESC1005X40X25NL10T10"
		(layer "B.Cu")
		(at 78.5216 130.0162)
		(property "Reference" "R17"
			(at 1.5714 0.126921 0)
			(unlocked yes)
			(layer "B.SilkS")
			(effects
				(font
					(size 0.762 0.762)
					(thickness 0.2286)
				)
				(justify mirror)
			)
		)
		(property "Value" "4.7K_1%_0402"
			(at -2.884671 -3.186595 270)
			(unlocked yes)
			(layer "B.SilkS")
			(hide yes)
			(effects
				(font
					(size 0.762 0.762)
					(thickness 0.2286)
				)
				(justify mirror)
			)
		)
		(sheetname "01-USER_IO")
		(sheetfile "01-USER_IO.kicad_sch")
		(duplicate_pad_numbers_are_jumpers no)
		(pad "1" smd rect
			(at -0.425 0 270)
			(size 0.6 0.65)
			(layers "B.Cu" "B.Mask" "B.Paste")
			(net "+3.3V")
		)
		(pad "2" smd rect
			(at 0.425 0 270)
			(size 0.6 0.65)
			(layers "B.Cu" "B.Mask" "B.Paste")
			(net "ANT3_IO_OUT")
		)
	)
	(footprint "Capacitors:CAPC1005X06N"
		(layer "B.Cu")
		(at 127.5802 151.7886 90)
		(property "Reference" "C46"
			(at 2.41349 -0.563055 270)
			(unlocked yes)
			(layer "B.SilkS")
			(effects
				(font
					(size 0.762 0.762)
					(thickness 0.2286)
				)
				(justify left bottom mirror)
			)
		)
		(property "Value" "CAP_0402_0.1UF_50V"
			(at -3.382645 0.2921 0)
			(unlocked yes)
			(layer "B.SilkS")
			(hide yes)
			(effects
				(font
					(size 0.762 0.762)
					(thickness 0.2286)
				)
				(justify left bottom mirror)
			)
		)
		(sheetname "04-PCIe_JTAG")
		(sheetfile "04-PCIe_JTAG.kicad_sch")
		(duplicate_pad_numbers_are_jumpers no)
		(pad "1" smd rect
			(at -0.43 0)
			(size 0.64 0.68)
			(layers "B.Cu" "B.Mask" "B.Paste")
			(net "NetC46_1")
		)
		(pad "2" smd rect
			(at 0.43 0)
			(size 0.64 0.68)
			(layers "B.Cu" "B.Mask" "B.Paste")
			(net "PCIE_TX0_P")
		)
	)
	(footprint "Vault:RESC1608X55X30NL15T15"
		(layer "B.Cu")
		(at 79.4216 50.9662 180)
		(property "Reference" "R35"
			(at -3.0714 -0.176931 0)
			(unlocked yes)
			(layer "B.SilkS")
			(effects
				(font
					(size 0.762 0.762)
					(thickness 0.2286)
				)
				(justify mirror)
			)
		)
		(property "Value" "200 OHM"
			(at -2.935471 -4.78626 90)
			(unlocked yes)
			(layer "B.SilkS")
			(hide yes)
			(effects
				(font
					(size 0.762 0.762)
					(thickness 0.2286)
				)
				(justify mirror)
			)
		)
		(sheetname "02-USER_IO_STATUS")
		(sheetfile "02-USER_IO_STATUS.kicad_sch")
		(duplicate_pad_numbers_are_jumpers no)
		(pad "1" smd rect
			(at -0.675 0 90)
			(size 0.95 0.8)
			(layers "B.Cu" "B.Mask" "B.Paste")
			(net "LED1")
		)
		(pad "2" smd rect
			(at 0.675 0 90)
			(size 0.95 0.8)
			(layers "B.Cu" "B.Mask" "B.Paste")
			(net "NetD3_1")
		)
	)
)
